# T6G (Grand Teton) — schematic netlist excerpt (pin names and nets, part order shuffled) for the footprints in the layout excerpt that follows; sources: Cadence DE-HDL packaged netlist, KiCad conversion of 04192023_DAF0TMB3IC0_F0TG_MB_C_brd_V02_OCP.brd

U314  9ZXL0451EKILFT  IC  pkg VFQFPN32_TH_0-5_5X5XD  page 182
  \^ckpwrgd_pd#\  = FM_9ZXL045_P0_DEV_EN
  VDDR  = P3V3_9ZXL045_P0_VDDR
  DIF_IN  = CLK_100M_CPU0_CLK13_DP
  \dif_in#\  = CLK_100M_CPU0_CLK13_DN
  VSADR0_TRI  = CLK_9ZXL045_P0_SADR0
  SMBDAT  = SMB_9ZXL045_P0_SDA
  SMBCLK  = SMB_9ZXL045_P0_SCL
  \fbout_nc#\  = NC_U314_FBOUT_N
  FBOUT_NC  = NC_U314_FBOUT
  NC0  = NC_U314_NC0
  NC1  = NC_U314_NC1
  VDD0  = P3V3_9ZXL045_P0_VDD
  DIF0  = CLK_100M_RETIMER_CPU0_P0_R_DP
  \dif0#\  = CLK_100M_RETIMER_CPU0_P0_R_DN
  \voe0#\  = FM_9ZXL045_P0_0_OE_N
  VDD1  = P3V3_9ZXL045_P0_VDD
  NC2  = NC_U314_NC2
  \voe1#\  = FM_9ZXL045_P0_1_OE_N
  DIF1  = CLK_100M_RETIMER_CPU0_P1_R_DP
  \dif1#\  = CLK_100M_RETIMER_CPU0_P1_R_DN
  VDD2  = P3V3_9ZXL045_P0_VDD
  DIF2  = CLK_100M_RETIMER_CPU0_P2_R_DP
  \dif2#\  = CLK_100M_RETIMER_CPU0_P2_R_DN
  \voe2#\  = FM_9ZXL045_P0_2_OE_N
  VDD3  = P3V3_9ZXL045_P0_VDD
  \voe3#\  = FM_9ZXL045_P0_3_OE_N
  DIF3  = CLK_100M_RETIMER_CPU0_P3_R_DP
  \dif3#\  = CLK_100M_RETIMER_CPU0_P3_R_DN
  VDD4  = P3V3_9ZXL045_P0_VDD
  NC3  = NC_U314_NC3
  VDDA  = P3V3_9ZXL045_P0_VDDA
  \^hibw_bypm_lobw#\  = CLK_9ZXL045_P0_HIBW
  EPAD_GND  = GND

(kicad_pcb
	(version 20260206)
	(generator "pcbnew")
	(generator_version "10.0")
	(general
		(thickness 1.6)
		(legacy_teardrops no)
	)
	(paper "A4")
	(title_block
		(title "04192023_DAF0TMB3IC0_F0TG_MB_C_brd_V02_OCP.brd")
		(comment 1 "Grand Teton / footprint 2170 of 8354 (U314), pads 1-33 of 33")
	)
	(layers
		(0 "F.Cu" signal "TOP")
		(4 "In1.Cu" signal "GND")
		(6 "In2.Cu" signal "IN1")
		(8 "In3.Cu" signal "GND1")
		(10 "In4.Cu" signal "IN2")
		(12 "In5.Cu" signal "GND2")
		(14 "In6.Cu" signal "IN3")
		(16 "In7.Cu" signal "GND3")
		(18 "In8.Cu" signal "VCC")
		(20 "In9.Cu" signal "VCC1")
		(22 "In10.Cu" signal "GND4")
		(24 "In11.Cu" signal "IN4")
		(26 "In12.Cu" signal "GND5")
		(28 "In13.Cu" signal "IN5")
		(30 "In14.Cu" signal "GND6")
		(32 "In15.Cu" signal "IN6")
		(34 "In16.Cu" signal "GND7")
		(2 "B.Cu" signal "BOTTOM")
		(9 "F.Adhes" user "F.Adhesive")
		(11 "B.Adhes" user "B.Adhesive")
		(13 "F.Paste" user "Package Geometry/Pastemask Top")
		(15 "B.Paste" user "Package Geometry/Pastemask Bottom")
		(5 "F.SilkS" user "Ref Des/Silkscreen Top")
		(7 "B.SilkS" user "Ref Des/Silkscreen Bottom")
		(1 "F.Mask" user "Board Geometry/Soldermask Top")
		(3 "B.Mask" user "Board Geometry/Soldermask Bottom")
		(17 "Dwgs.User" user "User.Drawings")
		(19 "Cmts.User" user "User.Comments")
		(21 "Eco1.User" user "User.Eco1")
		(23 "Eco2.User" user "User.Eco2")
		(25 "Edge.Cuts" user "Board Geometry/Outline")
		(27 "Margin" user)
		(31 "F.CrtYd" user "Package Geometry/Place Bound Top")
		(29 "B.CrtYd" user "Package Geometry/Place Bound Bottom")
		(35 "F.Fab" user "Ref Des/Assembly Top")
		(33 "B.Fab" user "Ref Des/Assembly Bottom")
	)
	(footprint ""
		(layer "F.Cu")
		(at 285.881064 -418.323014)
		(property "Reference" "U314"
			(at -0.34671 3.762248 0)
			(unlocked yes)
			(layer "F.SilkS")
			(effects
				(font
					(size 0.7874 0.5842)
					(thickness 0.1524)
				)
			)
		)
		(property "Value" ""
			(at 0 0 0)
			(layer "F.Fab")
			(effects
				(font
					(size 1.27 1.27)
				)
			)
		)
		(duplicate_pad_numbers_are_jumpers no)
		(pad "1" smd rect
			(at -2.3749 -1.75006 270)
			(size 0.254 0.5588)
			(layers "F.Cu" "F.Mask" "F.Paste")
			(net "FM_9ZXL045_P0_DEV_EN")
		)
		(pad "2" smd rect
			(at -2.3749 -1.249934 270)
			(size 0.254 0.5588)
			(layers "F.Cu" "F.Mask" "F.Paste")
			(net "P3V3_9ZXL045_P0_VDDR")
		)
		(pad "3" smd rect
			(at -2.3749 -0.750062 270)
			(size 0.254 0.5588)
			(layers "F.Cu" "F.Mask" "F.Paste")
			(net "CLK_100M_CPU0_CLK13_DP")
		)
		(pad "4" smd rect
			(at -2.3749 -0.249936 270)
			(size 0.254 0.5588)
			(layers "F.Cu" "F.Mask" "F.Paste")
			(net "CLK_100M_CPU0_CLK13_DN")
		)
		(pad "5" smd rect
			(at -2.3749 0.249936 270)
			(size 0.254 0.5588)
			(layers "F.Cu" "F.Mask" "F.Paste")
			(net "CLK_9ZXL045_P0_SADR0")
		)
		(pad "6" smd rect
			(at -2.3749 0.750062 270)
			(size 0.254 0.5588)
			(layers "F.Cu" "F.Mask" "F.Paste")
			(net "SMB_9ZXL045_P0_SDA")
		)
		(pad "7" smd rect
			(at -2.3749 1.249934 270)
			(size 0.254 0.5588)
			(layers "F.Cu" "F.Mask" "F.Paste")
			(net "SMB_9ZXL045_P0_SCL")
		)
		(pad "8" smd rect
			(at -2.3749 1.75006 270)
			(size 0.254 0.5588)
			(layers "F.Cu" "F.Mask" "F.Paste")
			(net "NC_U314_FBOUT_N")
		)
		(pad "9" smd rect
			(at -1.75006 2.3749)
			(size 0.254 0.5588)
			(layers "F.Cu" "F.Mask" "F.Paste")
			(net "NC_U314_FBOUT")
		)
		(pad "10" smd rect
			(at -1.249934 2.3749)
			(size 0.254 0.5588)
			(layers "F.Cu" "F.Mask" "F.Paste")
			(net "NC_U314_NC0")
		)
		(pad "11" smd rect
			(at -0.750062 2.3749)
			(size 0.254 0.5588)
			(layers "F.Cu" "F.Mask" "F.Paste")
			(net "NC_U314_NC1")
		)
		(pad "12" smd rect
			(at -0.249936 2.3749)
			(size 0.254 0.5588)
			(layers "F.Cu" "F.Mask" "F.Paste")
			(net "P3V3_9ZXL045_P0_VDD")
		)
		(pad "13" smd rect
			(at 0.249936 2.3749)
			(size 0.254 0.5588)
			(layers "F.Cu" "F.Mask" "F.Paste")
			(net "CLK_100M_RETIMER_CPU0_P0_R_DP")
		)
		(pad "14" smd rect
			(at 0.750062 2.3749)
			(size 0.254 0.5588)
			(layers "F.Cu" "F.Mask" "F.Paste")
			(net "CLK_100M_RETIMER_CPU0_P0_R_DN")
		)
		(pad "15" smd rect
			(at 1.249934 2.3749)
			(size 0.254 0.5588)
			(layers "F.Cu" "F.Mask" "F.Paste")
			(net "FM_9ZXL045_P0_0_OE_N")
		)
		(pad "16" smd rect
			(at 1.75006 2.3749)
			(size 0.254 0.5588)
			(layers "F.Cu" "F.Mask" "F.Paste")
			(net "P3V3_9ZXL045_P0_VDD")
		)
		(pad "17" smd rect
			(at 2.3749 1.75006 90)
			(size 0.254 0.5588)
			(layers "F.Cu" "F.Mask" "F.Paste")
			(net "NC_U314_NC2")
		)
		(pad "18" smd rect
			(at 2.3749 1.249934 90)
			(size 0.254 0.5588)
			(layers "F.Cu" "F.Mask" "F.Paste")
			(net "FM_9ZXL045_P0_1_OE_N")
		)
		(pad "19" smd rect
			(at 2.3749 0.750062 90)
			(size 0.254 0.5588)
			(layers "F.Cu" "F.Mask" "F.Paste")
			(net "CLK_100M_RETIMER_CPU0_P1_R_DP")
		)
		(pad "20" smd rect
			(at 2.3749 0.249936 90)
			(size 0.254 0.5588)
			(layers "F.Cu" "F.Mask" "F.Paste")
			(net "CLK_100M_RETIMER_CPU0_P1_R_DN")
		)
		(pad "21" smd rect
			(at 2.3749 -0.249936 90)
			(size 0.254 0.5588)
			(layers "F.Cu" "F.Mask" "F.Paste")
			(net "P3V3_9ZXL045_P0_VDD")
		)
		(pad "22" smd rect
			(at 2.3749 -0.750062 90)
			(size 0.254 0.5588)
			(layers "F.Cu" "F.Mask" "F.Paste")
			(net "CLK_100M_RETIMER_CPU0_P2_R_DP")
		)
		(pad "23" smd rect
			(at 2.3749 -1.249934 90)
			(size 0.254 0.5588)
			(layers "F.Cu" "F.Mask" "F.Paste")
			(net "CLK_100M_RETIMER_CPU0_P2_R_DN")
		)
		(pad "24" smd rect
			(at 2.3749 -1.75006 90)
			(size 0.254 0.5588)
			(layers "F.Cu" "F.Mask" "F.Paste")
			(net "FM_9ZXL045_P0_2_OE_N")
		)
		(pad "25" smd rect
			(at 1.75006 -2.3749 180)
			(size 0.254 0.5588)
			(layers "F.Cu" "F.Mask" "F.Paste")
			(net "P3V3_9ZXL045_P0_VDD")
		)
		(pad "26" smd rect
			(at 1.249934 -2.3749 180)
			(size 0.254 0.5588)
			(layers "F.Cu" "F.Mask" "F.Paste")
			(net "FM_9ZXL045_P0_3_OE_N")
		)
		(pad "27" smd rect
			(at 0.750062 -2.3749 180)
			(size 0.254 0.5588)
			(layers "F.Cu" "F.Mask" "F.Paste")
			(net "CLK_100M_RETIMER_CPU0_P3_R_DP")
		)
		(pad "28" smd rect
			(at 0.249936 -2.3749 180)
			(size 0.254 0.5588)
			(layers "F.Cu" "F.Mask" "F.Paste")
			(net "CLK_100M_RETIMER_CPU0_P3_R_DN")
		)
		(pad "29" smd rect
			(at -0.249936 -2.3749 180)
			(size 0.254 0.5588)
			(layers "F.Cu" "F.Mask" "F.Paste")
			(net "P3V3_9ZXL045_P0_VDD")
		)
		(pad "30" smd rect
			(at -0.750062 -2.3749 180)
			(size 0.254 0.5588)
			(layers "F.Cu" "F.Mask" "F.Paste")
			(net "NC_U314_NC3")
		)
		(pad "31" smd rect
			(at -1.249934 -2.3749 180)
			(size 0.254 0.5588)
			(layers "F.Cu" "F.Mask" "F.Paste")
			(net "P3V3_9ZXL045_P0_VDDA")
		)
		(pad "32" smd rect
			(at -1.75006 -2.3749 180)
			(size 0.254 0.5588)
			(layers "F.Cu" "F.Mask" "F.Paste")
			(net "CLK_9ZXL045_P0_HIBW")
		)
		(pad "33" smd rect
			(at 0 0)
			(size 3.1496 3.1496)
			(layers "F.Cu" "F.Mask" "F.Paste")
			(net "GND")
		)
	)
)
